# T6G (Grand Teton) — schematic netlist excerpt (pin names and nets, part order shuffled) for the footprints in the layout excerpt that follows; sources: Cadence DE-HDL packaged netlist, KiCad conversion of 04192023_DAF0TMB3IC0_F0TG_MB_C_brd_V02_OCP.brd

J100  SCONN288_DDR506112002KQ  IO  pkg DDR288S_1-1VXC  page 106
  VIN_BULK0  = P12V_MEM_CPU1
  RFU0  = NC
  VIN_MGMT  = P3V3_AUX
  HSCL  = I3C_SPD_DDRI_CPU1_SCL
  HSDA  = I3C_SPD_DDRI_CPU1_SDA
  VSS0  = GND
  DQ0_A  = M_I_CPU1_SA_DQ<0>
  VSS1  = GND
  DQ1_A  = M_I_CPU1_SA_DQ<1>
  VSS2  = GND
  DQS0_A_T  = M_I_CPU1_SA_DQS_DP<0>
  DQS0_A_C  = M_I_CPU1_SA_DQS_DN<0>
  VSS3  = GND
  DQ4_A  = M_I_CPU1_SA_DQ<4>
  VSS4  = GND
  DQ5_A  = M_I_CPU1_SA_DQ<5>
  VSS5  = GND
  DQ8_A  = M_I_CPU1_SA_DQ<8>
  VSS6  = GND
  DQ9_A  = M_I_CPU1_SA_DQ<9>
  VSS7  = GND
  DQS1_A_T  = M_I_CPU1_SA_DQS_DP<1>
  DQS1_A_C  = M_I_CPU1_SA_DQS_DN<1>
  VSS8  = GND
  DQ12_A  = M_I_CPU1_SA_DQ<12>
  VSS9  = GND
  DQ13_A  = M_I_CPU1_SA_DQ<13>
  VSS10  = GND
  DQ16_A  = M_I_CPU1_SA_DQ<16>
  VSS11  = GND
  DQ17_A  = M_I_CPU1_SA_DQ<17>
  VSS12  = GND
  DQS2_A_T  = M_I_CPU1_SA_DQS_DP<2>
  DQS2_A_C  = M_I_CPU1_SA_DQS_DN<2>
  VSS13  = GND
  DQ20_A  = M_I_CPU1_SA_DQ<20>
  VSS14  = GND
  DQ21_A  = M_I_CPU1_SA_DQ<21>
  VSS15  = GND
  DQ24_A  = M_I_CPU1_SA_DQ<24>
  VSS16  = GND
  DQ25_A  = M_I_CPU1_SA_DQ<25>
  VSS17  = GND
  DQS3_A_T  = M_I_CPU1_SA_DQS_DP<3>
  DQS3_A_C  = M_I_CPU1_SA_DQS_DN<3>
  VSS18  = GND
  DQ28_A  = M_I_CPU1_SA_DQ<28>
  VSS19  = GND
  DQ29_A  = M_I_CPU1_SA_DQ<29>
  VSS20  = GND
  CB0_A  = M_I_CPU1_SA_CB<0>
  VSS21  = GND
  CB1_A  = M_I_CPU1_SA_CB<1>
  VSS22  = GND
  DQS4_A_T  = M_I_CPU1_SA_DQS_DP<4>
  DQS4_A_C  = M_I_CPU1_SA_DQS_DN<4>
  VSS23  = GND
  CB4_A  = M_I_CPU1_SA_CB<4>
  VSS24  = GND
  CB5_A  = M_I_CPU1_SA_CB<5>
  VSS25  = GND
  ALERT_N  = M_I_CPU1_ALERT_N
  VSS26  = GND
  CS0_A_N  = M_I_CPU1_SA_CS_N<0>
  VSS27  = GND
  CA0_A  = M_I_CPU1_SA_CA<0>
  VSS28  = GND
  CA2_A  = M_I_CPU1_SA_CA<2>
  VSS29  = GND
  CA4_A  = M_I_CPU1_SA_CA<4>
  VSS30  = GND
  CA6_A  = M_I_CPU1_SA_CA<6>
  VSS31  = GND
  PAR_A  = M_I_CPU1_SA_PAR
  VSS32  = GND
  CA0_B  = M_I_CPU1_SB_CA<0>
  VSS33  = GND
  CA2_B  = M_I_CPU1_SB_CA<2>
  VSS34  = GND
  CA4_B  = M_I_CPU1_SB_CA<4>
  VSS35  = GND
  CA6_B  = M_I_CPU1_SB_CA<6>
  VSS36  = GND
  CS0_B_N  = M_I_CPU1_SB_CS_N<0>
  VSS37  = GND
  \lbd||rsp_a_n\  = M_I_CPU1_SA_RSP<0>
  \lbs||rsp_b_n\  = M_I_CPU1_SB_RSP<0>
  VSS38  = GND
  CB4_B  = M_I_CPU1_SB_CB<4>
  VSS39  = GND
  CB5_B  = M_I_CPU1_SB_CB<5>
  VSS40  = GND
  \dqs9_b_t||tdqs9_b_t||dbi4_b_n\  = M_I_CPU1_SB_DQS_DP<9>
  \dqs9_b_c||tdqs9_b_c\  = M_I_CPU1_SB_DQS_DN<9>
  VSS41  = GND
  CB0_B  = M_I_CPU1_SB_CB<0>
  VSS42  = GND
  CB1_B  = M_I_CPU1_SB_CB<1>
  VSS43  = GND
  DQ0_B  = M_I_CPU1_SB_DQ<0>
  VSS44  = GND
  DQ1_B  = M_I_CPU1_SB_DQ<1>
  VSS45  = GND
  DQS0_B_T  = M_I_CPU1_SB_DQS_DP<0>
  DQS0_B_C  = M_I_CPU1_SB_DQS_DN<0>
  VSS46  = GND
  DQ4_B  = M_I_CPU1_SB_DQ<4>
  VSS47  = GND
  DQ5_B  = M_I_CPU1_SB_DQ<5>
  VSS48  = GND
  DQ8_B  = M_I_CPU1_SB_DQ<8>
  VSS49  = GND
  DQ9_B  = M_I_CPU1_SB_DQ<9>
  VSS50  = GND
  DQS1_B_T  = M_I_CPU1_SB_DQS_DP<1>
  DQS1_B_C  = M_I_CPU1_SB_DQS_DN<1>
  VSS51  = GND
  DQ12_B  = M_I_CPU1_SB_DQ<12>
  VSS52  = GND
  DQ13_B  = M_I_CPU1_SB_DQ<13>
  VSS53  = GND
  DQ16_B  = M_I_CPU1_SB_DQ<16>
  VSS54  = GND
  DQ17_B  = M_I_CPU1_SB_DQ<17>
  VSS55  = GND
  DQS2_B_T  = M_I_CPU1_SB_DQS_DP<2>
  DQS2_B_C  = M_I_CPU1_SB_DQS_DN<2>
  VSS56  = GND
  DQ20_B  = M_I_CPU1_SB_DQ<20>
  VSS57  = GND
  DQ21_B  = M_I_CPU1_SB_DQ<21>
  VSS58  = GND
  DQ24_B  = M_I_CPU1_SB_DQ<24>
  VSS59  = GND
  DQ25_B  = M_I_CPU1_SB_DQ<25>
  VSS60  = GND
  DQS3_B_T  = M_I_CPU1_SB_DQS_DP<3>
  DQS3_B_C  = M_I_CPU1_SB_DQS_DN<3>
  VSS61  = GND
  DQ28_B  = M_I_CPU1_SB_DQ<28>
  VSS62  = GND
  DQ29_B  = M_I_CPU1_SB_DQ<29>
  VSS63  = GND
  RFU1  = NC
  VIN_BULK1  = P12V_MEM_CPU1
  VIN_BULK2  = P12V_MEM_CPU1
  \pwr_good||fail_n\  = PWRGD_CHI_CPU1_DIMM
  HAS  = PD_CHI_CPU1_DIMM_SAA
  RFU2  = NC
  RFU3  = NC
  VSS64  = GND
  DQ2_A  = M_I_CPU1_SA_DQ<2>
  VSS65  = GND
  DQ3_A  = M_I_CPU1_SA_DQ<3>
  VSS66  = GND
  \dqs5_a_c||tdqs5_a_c||dqs5_a_t||tdqs5_a_t\  = M_I_CPU1_SA_DQS_DN<5>
  \dqs5_a_t||tdqs5_a_t\  = M_I_CPU1_SA_DQS_DP<5>
  VSS67  = GND
  DQ6_A  = M_I_CPU1_SA_DQ<6>
  VSS68  = GND
  DQ7_A  = M_I_CPU1_SA_DQ<7>
  VSS69  = GND
  DQ10_A  = M_I_CPU1_SA_DQ<10>
  VSS70  = GND
  DQ11_A  = M_I_CPU1_SA_DQ<11>
  VSS71  = GND
  \dqs6_a_c||tdqs6_a_c||dqs6_a_t||tdqs6_a_t\  = M_I_CPU1_SA_DQS_DN<6>
  \dqs6_a_t||tdqs6_a_t\  = M_I_CPU1_SA_DQS_DP<6>
  VSS72  = GND
  DQ14_A  = M_I_CPU1_SA_DQ<14>
  VSS73  = GND
  DQ15_A  = M_I_CPU1_SA_DQ<15>
  VSS74  = GND
  DQ18_A  = M_I_CPU1_SA_DQ<18>
  VSS75  = GND
  DQ19_A  = M_I_CPU1_SA_DQ<19>
  VSS76  = GND
  \dqs7_a_c||tdqs7_a_c\  = M_I_CPU1_SA_DQS_DN<7>
  \dqs7_a_t||tdqs7_a_t\  = M_I_CPU1_SA_DQS_DP<7>
  VSS77  = GND
  DQ22_A  = M_I_CPU1_SA_DQ<22>
  VSS78  = GND
  DQ23_A  = M_I_CPU1_SA_DQ<23>
  VSS79  = GND
  DQ26_A  = M_I_CPU1_SA_DQ<26>
  VSS80  = GND
  DQ27_A  = M_I_CPU1_SA_DQ<27>
  VSS81  = GND
  \dqs8_a_c||tdqs8_a_c\  = M_I_CPU1_SA_DQS_DN<8>
  \dqs8_a_t||tdqs8_a_t\  = M_I_CPU1_SA_DQS_DP<8>
  VSS82  = GND
  DQ30_A  = M_I_CPU1_SA_DQ<30>
  VSS83  = GND
  DQ31_A  = M_I_CPU1_SA_DQ<31>
  VSS84  = GND
  CB2_A  = M_I_CPU1_SA_CB<2>
  VSS85  = GND
  CB3_A  = M_I_CPU1_SA_CB<3>
  VSS86  = GND
  \dqs9_a_c||tdqs9_a_c\  = M_I_CPU1_SA_DQS_DN<9>
  \dqs9_a_t||tdqs9_a_t\  = M_I_CPU1_SA_DQS_DP<9>
  VSS87  = GND
  CB6_A  = M_I_CPU1_SA_CB<6>
  VSS88  = GND
  CB7_A  = M_I_CPU1_SA_CB<7>
  VSS89  = GND
  RESET_N  = M_I_CPU1_RESET_N
  VSS90  = GND
  CS1_A_N  = M_I_CPU1_SA_CS_N<1>
  VSS91  = GND
  CA1_A  = M_I_CPU1_SA_CA<1>
  VSS92  = GND
  CA3_A  = M_I_CPU1_SA_CA<3>
  VSS93  = GND
  CA5_A  = M_I_CPU1_SA_CA<5>
  VSS94  = GND
  CK_T  = M_I_CPU1_CLK_DP<0>
  CK_C  = M_I_CPU1_CLK_DN<0>
  VSS95  = GND
  RFU4  = NC
  CA1_B  = M_I_CPU1_SB_CA<1>
  VSS96  = GND
  CA3_B  = M_I_CPU1_SB_CA<3>
  VSS97  = GND
  CA5_B  = M_I_CPU1_SB_CA<5>
  VSS98  = GND
  PAR_B  = M_I_CPU1_SB_PAR
  VSS99  = GND
  CS1_B_N  = M_I_CPU1_SB_CS_N<1>
  VSS100  = GND
  RFU5  = NC
  RFU6  = NC
  VSS101  = GND
  CB6_B  = M_I_CPU1_SB_CB<6>
  VSS102  = GND
  CB7_B  = M_I_CPU1_SB_CB<7>
  VSS103  = GND
  DQS4_B_C  = M_I_CPU1_SB_DQS_DN<4>
  DQS4_B_T  = M_I_CPU1_SB_DQS_DP<4>
  VSS104  = GND
  CB2_B  = M_I_CPU1_SB_CB<2>
  VSS105  = GND
  CB3_B  = M_I_CPU1_SB_CB<3>
  VSS106  = GND
  DQ2_B  = M_I_CPU1_SB_DQ<2>
  VSS107  = GND
  DQ3_B  = M_I_CPU1_SB_DQ<3>
  VSS108  = GND
  \dqs5_b_c||tdqs5_b_c\  = M_I_CPU1_SB_DQS_DN<5>
  \dqs5_b_t||tdqs5_b_t\  = M_I_CPU1_SB_DQS_DP<5>
  VSS109  = GND
  DQ6_B  = M_I_CPU1_SB_DQ<6>
  VSS110  = GND
  DQ7_B  = M_I_CPU1_SB_DQ<7>
  VSS111  = GND
  DQ10_B  = M_I_CPU1_SB_DQ<10>
  VSS112  = GND
  DQ11_B  = M_I_CPU1_SB_DQ<11>
  VSS113  = GND
  \dqs6_b_c||tdqs6_b_c\  = M_I_CPU1_SB_DQS_DN<6>
  \dqs6_b_t||tdqs6_b_t\  = M_I_CPU1_SB_DQS_DP<6>
  VSS114  = GND
  DQ14_B  = M_I_CPU1_SB_DQ<14>
  VSS115  = GND
  DQ15_B  = M_I_CPU1_SB_DQ<15>
  VSS116  = GND
  DQ18_B  = M_I_CPU1_SB_DQ<18>
  VSS117  = GND
  DQ19_B  = M_I_CPU1_SB_DQ<19>
  VSS118  = GND
  \dqs7_b_c||tdqs7_b_c\  = M_I_CPU1_SB_DQS_DN<7>
  \dqs7_b_t||tdqs7_b_t\  = M_I_CPU1_SB_DQS_DP<7>
  VSS119  = GND
  DQ22_B  = M_I_CPU1_SB_DQ<22>
  VSS120  = GND
  DQ23_B  = M_I_CPU1_SB_DQ<23>
  VSS121  = GND
  DQ26_B  = M_I_CPU1_SB_DQ<26>
  VSS122  = GND
  DQ27_B  = M_I_CPU1_SB_DQ<27>
  VSS123  = GND
  \dqs8_b_c||tdqs8_b_c\  = M_I_CPU1_SB_DQS_DN<8>
  \dqs8_b_t||tdqs8_b_t\  = M_I_CPU1_SB_DQS_DP<8>
  VSS124  = GND
  DQ30_B  = M_I_CPU1_SB_DQ<30>
  VSS125  = GND
  DQ31_B  = M_I_CPU1_SB_DQ<31>
  VSS126  = GND
  G1  = GND
  G2  = GND
  G3  = GND

(kicad_pcb
	(version 20260206)
	(generator "pcbnew")
	(generator_version "10.0")
	(general
		(thickness 1.6)
		(legacy_teardrops no)
	)
	(paper "A4")
	(title_block
		(title "04192023_DAF0TMB3IC0_F0TG_MB_C_brd_V02_OCP.brd")
		(comment 1 "Grand Teton / footprint 230 of 8354 (J100), pads 47-92 of 291")
	)
	(layers
		(0 "F.Cu" signal "TOP")
		(4 "In1.Cu" signal "GND")
		(6 "In2.Cu" signal "IN1")
		(8 "In3.Cu" signal "GND1")
		(10 "In4.Cu" signal "IN2")
		(12 "In5.Cu" signal "GND2")
		(14 "In6.Cu" signal "IN3")
		(16 "In7.Cu" signal "GND3")
		(18 "In8.Cu" signal "VCC")
		(20 "In9.Cu" signal "VCC1")
		(22 "In10.Cu" signal "GND4")
		(24 "In11.Cu" signal "IN4")
		(26 "In12.Cu" signal "GND5")
		(28 "In13.Cu" signal "IN5")
		(30 "In14.Cu" signal "GND6")
		(32 "In15.Cu" signal "IN6")
		(34 "In16.Cu" signal "GND7")
		(2 "B.Cu" signal "BOTTOM")
		(9 "F.Adhes" user "F.Adhesive")
		(11 "B.Adhes" user "B.Adhesive")
		(13 "F.Paste" user "Package Geometry/Pastemask Top")
		(15 "B.Paste" user "Package Geometry/Pastemask Bottom")
		(5 "F.SilkS" user "Ref Des/Silkscreen Top")
		(7 "B.SilkS" user "Ref Des/Silkscreen Bottom")
		(1 "F.Mask" user "Board Geometry/Soldermask Top")
		(3 "B.Mask" user "Board Geometry/Soldermask Bottom")
		(17 "Dwgs.User" user "User.Drawings")
		(19 "Cmts.User" user "User.Comments")
		(21 "Eco1.User" user "User.Eco1")
		(23 "Eco2.User" user "User.Eco2")
		(25 "Edge.Cuts" user "Board Geometry/Outline")
		(27 "Margin" user)
		(31 "F.CrtYd" user "Package Geometry/Place Bound Top")
		(29 "B.CrtYd" user "Package Geometry/Place Bound Bottom")
		(35 "F.Fab" user "Ref Des/Assembly Top")
		(33 "B.Fab" user "Ref Des/Assembly Bottom")
	)
	(footprint ""
		(layer "F.Cu")
		(at 181.566058 -255.560322 180)
		(property "Reference" "J100"
			(at -2.7178 -81.857088 0)
			(unlocked yes)
			(layer "F.SilkS")
			(effects
				(font
					(size 0.7874 0.5842)
					(thickness 0.1524)
				)
			)
		)
		(property "Value" ""
			(at 0 0 180)
			(layer "F.Fab")
			(effects
				(font
					(size 1.27 1.27)
				)
			)
		)
		(duplicate_pad_numbers_are_jumpers no)
		(pad "47" smd rect
			(at -2.050034 -24.224996 90)
			(size 0.519938 1.4986)
			(layers "F.Cu" "F.Mask" "F.Paste")
			(net "M_I_CPU1_SA_DQ<28>")
		)
		(pad "48" smd rect
			(at -2.050034 -23.375112 90)
			(size 0.519938 1.4986)
			(layers "F.Cu" "F.Mask" "F.Paste")
			(net "GND")
		)
		(pad "49" smd rect
			(at -2.050034 -22.524974 90)
			(size 0.519938 1.4986)
			(layers "F.Cu" "F.Mask" "F.Paste")
			(net "M_I_CPU1_SA_DQ<29>")
		)
		(pad "50" smd rect
			(at -2.050034 -21.67509 90)
			(size 0.519938 1.4986)
			(layers "F.Cu" "F.Mask" "F.Paste")
			(net "GND")
		)
		(pad "51" smd rect
			(at -2.050034 -20.824952 90)
			(size 0.519938 1.4986)
			(layers "F.Cu" "F.Mask" "F.Paste")
			(net "M_I_CPU1_SA_CB<0>")
		)
		(pad "52" smd rect
			(at -2.050034 -19.975068 90)
			(size 0.519938 1.4986)
			(layers "F.Cu" "F.Mask" "F.Paste")
			(net "GND")
		)
		(pad "53" smd rect
			(at -2.050034 -19.12493 90)
			(size 0.519938 1.4986)
			(layers "F.Cu" "F.Mask" "F.Paste")
			(net "M_I_CPU1_SA_CB<1>")
		)
		(pad "54" smd rect
			(at -2.050034 -18.275046 90)
			(size 0.519938 1.4986)
			(layers "F.Cu" "F.Mask" "F.Paste")
			(net "GND")
		)
		(pad "55" smd rect
			(at -2.050034 -17.424908 90)
			(size 0.519938 1.4986)
			(layers "F.Cu" "F.Mask" "F.Paste")
			(net "M_I_CPU1_SA_DQS_DP<4>")
		)
		(pad "56" smd rect
			(at -2.050034 -16.575024 90)
			(size 0.519938 1.4986)
			(layers "F.Cu" "F.Mask" "F.Paste")
			(net "M_I_CPU1_SA_DQS_DN<4>")
		)
		(pad "57" smd rect
			(at -2.050034 -15.724886 90)
			(size 0.519938 1.4986)
			(layers "F.Cu" "F.Mask" "F.Paste")
			(net "GND")
		)
		(pad "58" smd rect
			(at -2.050034 -14.875002 90)
			(size 0.519938 1.4986)
			(layers "F.Cu" "F.Mask" "F.Paste")
			(net "M_I_CPU1_SA_CB<4>")
		)
		(pad "59" smd rect
			(at -2.050034 -14.025118 90)
			(size 0.519938 1.4986)
			(layers "F.Cu" "F.Mask" "F.Paste")
			(net "GND")
		)
		(pad "60" smd rect
			(at -2.050034 -13.17498 90)
			(size 0.519938 1.4986)
			(layers "F.Cu" "F.Mask" "F.Paste")
			(net "M_I_CPU1_SA_CB<5>")
		)
		(pad "61" smd rect
			(at -2.050034 -12.325096 90)
			(size 0.519938 1.4986)
			(layers "F.Cu" "F.Mask" "F.Paste")
			(net "GND")
		)
		(pad "62" smd rect
			(at -2.050034 -11.474958 90)
			(size 0.519938 1.4986)
			(layers "F.Cu" "F.Mask" "F.Paste")
			(net "M_I_CPU1_ALERT_N")
		)
		(pad "63" smd rect
			(at -2.050034 -10.625074 90)
			(size 0.519938 1.4986)
			(layers "F.Cu" "F.Mask" "F.Paste")
			(net "GND")
		)
		(pad "64" smd rect
			(at -2.050034 -9.774936 90)
			(size 0.519938 1.4986)
			(layers "F.Cu" "F.Mask" "F.Paste")
			(net "M_I_CPU1_SA_CS_N<0>")
		)
		(pad "65" smd rect
			(at -2.050034 -8.925052 90)
			(size 0.519938 1.4986)
			(layers "F.Cu" "F.Mask" "F.Paste")
			(net "GND")
		)
		(pad "66" smd rect
			(at -2.050034 -8.074914 90)
			(size 0.519938 1.4986)
			(layers "F.Cu" "F.Mask" "F.Paste")
			(net "M_I_CPU1_SA_CA<0>")
		)
		(pad "67" smd rect
			(at -2.050034 -7.22503 90)
			(size 0.519938 1.4986)
			(layers "F.Cu" "F.Mask" "F.Paste")
			(net "GND")
		)
		(pad "68" smd rect
			(at -2.050034 -6.374892 90)
			(size 0.519938 1.4986)
			(layers "F.Cu" "F.Mask" "F.Paste")
			(net "M_I_CPU1_SA_CA<2>")
		)
		(pad "69" smd rect
			(at -2.050034 -5.525008 90)
			(size 0.519938 1.4986)
			(layers "F.Cu" "F.Mask" "F.Paste")
			(net "GND")
		)
		(pad "70" smd rect
			(at -2.050034 -4.675124 90)
			(size 0.519938 1.4986)
			(layers "F.Cu" "F.Mask" "F.Paste")
			(net "M_I_CPU1_SA_CA<4>")
		)
		(pad "71" smd rect
			(at -2.050034 -3.824986 90)
			(size 0.519938 1.4986)
			(layers "F.Cu" "F.Mask" "F.Paste")
			(net "GND")
		)
		(pad "72" smd rect
			(at -2.050034 -2.975102 90)
			(size 0.519938 1.4986)
			(layers "F.Cu" "F.Mask" "F.Paste")
			(net "M_I_CPU1_SA_CA<6>")
		)
		(pad "73" smd rect
			(at -2.050034 -2.124964 90)
			(size 0.519938 1.4986)
			(layers "F.Cu" "F.Mask" "F.Paste")
			(net "GND")
		)
		(pad "74" smd rect
			(at -2.050034 -1.27508 90)
			(size 0.519938 1.4986)
			(layers "F.Cu" "F.Mask" "F.Paste")
			(net "M_I_CPU1_SA_PAR")
		)
		(pad "75" smd rect
			(at -2.050034 -0.424942 90)
			(size 0.519938 1.4986)
			(layers "F.Cu" "F.Mask" "F.Paste")
			(net "GND")
		)
		(pad "76" smd rect
			(at -2.050034 5.525008 90)
			(size 0.519938 1.4986)
			(layers "F.Cu" "F.Mask" "F.Paste")
			(net "M_I_CPU1_SB_CA<0>")
		)
		(pad "77" smd rect
			(at -2.050034 6.374892 90)
			(size 0.519938 1.4986)
			(layers "F.Cu" "F.Mask" "F.Paste")
			(net "GND")
		)
		(pad "78" smd rect
			(at -2.050034 7.22503 90)
			(size 0.519938 1.4986)
			(layers "F.Cu" "F.Mask" "F.Paste")
			(net "M_I_CPU1_SB_CA<2>")
		)
		(pad "79" smd rect
			(at -2.050034 8.074914 90)
			(size 0.519938 1.4986)
			(layers "F.Cu" "F.Mask" "F.Paste")
			(net "GND")
		)
		(pad "80" smd rect
			(at -2.050034 8.925052 90)
			(size 0.519938 1.4986)
			(layers "F.Cu" "F.Mask" "F.Paste")
			(net "M_I_CPU1_SB_CA<4>")
		)
		(pad "81" smd rect
			(at -2.050034 9.774936 90)
			(size 0.519938 1.4986)
			(layers "F.Cu" "F.Mask" "F.Paste")
			(net "GND")
		)
		(pad "82" smd rect
			(at -2.050034 10.625074 90)
			(size 0.519938 1.4986)
			(layers "F.Cu" "F.Mask" "F.Paste")
			(net "M_I_CPU1_SB_CA<6>")
		)
		(pad "83" smd rect
			(at -2.050034 11.474958 90)
			(size 0.519938 1.4986)
			(layers "F.Cu" "F.Mask" "F.Paste")
			(net "GND")
		)
		(pad "84" smd rect
			(at -2.050034 12.325096 90)
			(size 0.519938 1.4986)
			(layers "F.Cu" "F.Mask" "F.Paste")
			(net "M_I_CPU1_SB_CS_N<0>")
		)
		(pad "85" smd rect
			(at -2.050034 13.17498 90)
			(size 0.519938 1.4986)
			(layers "F.Cu" "F.Mask" "F.Paste")
			(net "GND")
		)
		(pad "86" smd rect
			(at -2.050034 14.025118 90)
			(size 0.519938 1.4986)
			(layers "F.Cu" "F.Mask" "F.Paste")
			(net "M_I_CPU1_SA_RSP<0>")
		)
		(pad "87" smd rect
			(at -2.050034 14.875002 90)
			(size 0.519938 1.4986)
			(layers "F.Cu" "F.Mask" "F.Paste")
			(net "M_I_CPU1_SB_RSP<0>")
		)
		(pad "88" smd rect
			(at -2.050034 15.724886 90)
			(size 0.519938 1.4986)
			(layers "F.Cu" "F.Mask" "F.Paste")
			(net "GND")
		)
		(pad "89" smd rect
			(at -2.050034 16.575024 90)
			(size 0.519938 1.4986)
			(layers "F.Cu" "F.Mask" "F.Paste")
			(net "M_I_CPU1_SB_CB<4>")
		)
		(pad "90" smd rect
			(at -2.050034 17.424908 90)
			(size 0.519938 1.4986)
			(layers "F.Cu" "F.Mask" "F.Paste")
			(net "GND")
		)
		(pad "91" smd rect
			(at -2.050034 18.275046 90)
			(size 0.519938 1.4986)
			(layers "F.Cu" "F.Mask" "F.Paste")
			(net "M_I_CPU1_SB_CB<5>")
		)
		(pad "92" smd rect
			(at -2.050034 19.12493 90)
			(size 0.519938 1.4986)
			(layers "F.Cu" "F.Mask" "F.Paste")
			(net "GND")
		)
	)
)
